(kicad_pcb
	(version 20260206)
	(generator "pcbnew")
	(generator_version "10.0")
	(general
		(thickness 1.6)
		(legacy_teardrops no)
	)
	(paper "A4")
	(title_block
		(title "12092022_DA0F0TFB6D0_F0T_FAN_BOARD_MP5048_D_brd_v02_OCP.brd")
		(comment 1 "Grand Teton / footprints 315-320 of 924")
	)
	(layers
		(0 "F.Cu" signal "TOP")
		(4 "In1.Cu" signal "GND")
		(6 "In2.Cu" signal "IN1")
		(8 "In3.Cu" signal "IN2")
		(10 "In4.Cu" signal "GND1")
		(2 "B.Cu" signal "BOTTOM")
		(9 "F.Adhes" user "F.Adhesive")
		(11 "B.Adhes" user "B.Adhesive")
		(13 "F.Paste" user "Package Geometry/Pastemask Top")
		(15 "B.Paste" user "Package Geometry/Pastemask Bottom")
		(5 "F.SilkS" user "Ref Des/Silkscreen Top")
		(7 "B.SilkS" user "Ref Des/Silkscreen Bottom")
		(1 "F.Mask" user "Board Geometry/Soldermask Top")
		(3 "B.Mask" user "Board Geometry/Soldermask Bottom")
		(17 "Dwgs.User" user "User.Drawings")
		(19 "Cmts.User" user "User.Comments")
		(21 "Eco1.User" user "User.Eco1")
		(23 "Eco2.User" user "User.Eco2")
		(25 "Edge.Cuts" user "Board Geometry/Outline")
		(27 "Margin" user)
		(31 "F.CrtYd" user "Package Geometry/Place Bound Top")
		(29 "B.CrtYd" user "Package Geometry/Place Bound Bottom")
		(35 "F.Fab" user "Ref Des/Assembly Top")
		(33 "B.Fab" user "Ref Des/Assembly Bottom")
	)
	(footprint ""
		(layer "F.Cu")
		(at 9.906 -173.228 180)
		(property "Reference" "U26"
			(at 2.00533 -1.016 90)
			(unlocked yes)
			(layer "F.SilkS")
			(effects
				(font
					(size 0.7874 0.5842)
					(thickness 0.1524)
				)
				(justify left)
			)
		)
		(property "Value" ""
			(at 0 0 180)
			(layer "F.Fab")
			(effects
				(font
					(size 1.27 1.27)
				)
			)
		)
		(duplicate_pad_numbers_are_jumpers no)
		(fp_line
			(start 1.3462 1.100074)
			(end -1.3462 1.100074)
			(stroke
				(width 0.1524)
				(type default)
			)
			(layer "F.SilkS")
		)
		(fp_line
			(start 1.3462 -1.100074)
			(end 1.3462 1.100074)
			(stroke
				(width 0.1524)
				(type default)
			)
			(layer "F.SilkS")
		)
		(fp_line
			(start 0.670052 -1.100074)
			(end 1.3462 -1.100074)
			(stroke
				(width 0.1524)
				(type default)
			)
			(layer "F.SilkS")
		)
		(fp_line
			(start 0 -0.381)
			(end 0.670052 -1.100074)
			(stroke
				(width 0.1524)
				(type default)
			)
			(layer "F.SilkS")
		)
		(fp_line
			(start -0.670052 -1.100074)
			(end 0 -0.381)
			(stroke
				(width 0.1524)
				(type default)
			)
			(layer "F.SilkS")
		)
		(fp_line
			(start -1.3462 1.100074)
			(end -1.3462 -1.100074)
			(stroke
				(width 0.1524)
				(type default)
			)
			(layer "F.SilkS")
		)
		(fp_line
			(start -1.3462 -1.100074)
			(end -0.670052 -1.100074)
			(stroke
				(width 0.1524)
				(type default)
			)
			(layer "F.SilkS")
		)
		(fp_poly
			(pts
				(xy -1.524 -0.649986) (xy -2.286 -1.030986) (xy -2.286 -0.268986)
			)
			(stroke
				(width 0)
				(type default)
			)
			(fill yes)
			(layer "F.SilkS")
		)
		(fp_line
			(start 1.100074 0.8001)
			(end 0.670052 0.8001)
			(stroke
				(width 0.1)
				(type default)
			)
			(layer "F.Fab")
		)
		(fp_line
			(start 1.100074 -0.8001)
			(end 1.100074 0.8001)
			(stroke
				(width 0.1)
				(type default)
			)
			(layer "F.Fab")
		)
		(fp_line
			(start 0.670052 1.100074)
			(end -0.670052 1.100074)
			(stroke
				(width 0.1)
				(type default)
			)
			(layer "F.Fab")
		)
		(fp_line
			(start 0.670052 0.8001)
			(end 0.670052 1.100074)
			(stroke
				(width 0.1)
				(type default)
			)
			(layer "F.Fab")
		)
		(fp_line
			(start 0.670052 -0.8001)
			(end 1.100074 -0.8001)
			(stroke
				(width 0.1)
				(type default)
			)
			(layer "F.Fab")
		)
		(fp_line
			(start 0.670052 -0.8001)
			(end 0.670052 0.8001)
			(stroke
				(width 0.1)
				(type default)
			)
			(layer "F.Fab")
		)
		(fp_line
			(start 0.670052 -1.100074)
			(end 0.670052 -0.8001)
			(stroke
				(width 0.1)
				(type default)
			)
			(layer "F.Fab")
		)
		(fp_line
			(start -0.670052 1.100074)
			(end -0.670052 0.8001)
			(stroke
				(width 0.1)
				(type default)
			)
			(layer "F.Fab")
		)
		(fp_line
			(start -0.670052 0.8001)
			(end -0.670052 -0.8001)
			(stroke
				(width 0.1)
				(type default)
			)
			(layer "F.Fab")
		)
		(fp_line
			(start -0.670052 0.8001)
			(end -1.100074 0.8001)
			(stroke
				(width 0.1)
				(type default)
			)
			(layer "F.Fab")
		)
		(fp_line
			(start -0.670052 -0.8001)
			(end -0.670052 -1.100074)
			(stroke
				(width 0.1)
				(type default)
			)
			(layer "F.Fab")
		)
		(fp_line
			(start -0.670052 -1.100074)
			(end 0.670052 -1.100074)
			(stroke
				(width 0.1)
				(type default)
			)
			(layer "F.Fab")
		)
		(fp_line
			(start -1.100074 0.8001)
			(end -1.100074 -0.8001)
			(stroke
				(width 0.1)
				(type default)
			)
			(layer "F.Fab")
		)
		(fp_line
			(start -1.100074 -0.8001)
			(end -0.670052 -0.8001)
			(stroke
				(width 0.1)
				(type default)
			)
			(layer "F.Fab")
		)
		(fp_poly
			(pts
				(xy -1.524 -0.649986) (xy -2.286 -1.030986) (xy -2.286 -0.268986)
			)
			(stroke
				(width 0)
				(type default)
			)
			(fill yes)
			(layer "F.Fab")
		)
		(pad "1" smd rect
			(at -0.94996 -0.649986 90)
			(size 0.4064 0.508)
			(layers "F.Cu" "F.Mask" "F.Paste")
			(net "FAN_6_PRESENT_N")
		)
		(pad "2" smd rect
			(at -0.94996 0 90)
			(size 0.4064 0.508)
			(layers "F.Cu" "F.Mask" "F.Paste")
			(net "GND")
		)
		(pad "3" smd rect
			(at -0.94996 0.649986 90)
			(size 0.4064 0.508)
			(layers "F.Cu" "F.Mask" "F.Paste")
			(net "FAN_7_PRESENT_N")
		)
		(pad "4" smd rect
			(at 0.94996 0.649986 90)
			(size 0.4064 0.508)
			(layers "F.Cu" "F.Mask" "F.Paste")
			(net "FAN_7_PRSNT_BUF_R_N")
		)
		(pad "5" smd rect
			(at 0.94996 0 90)
			(size 0.4064 0.508)
			(layers "F.Cu" "F.Mask" "F.Paste")
			(net "P3V3_AUX")
		)
		(pad "6" smd rect
			(at 0.94996 -0.649986 90)
			(size 0.4064 0.508)
			(layers "F.Cu" "F.Mask" "F.Paste")
			(net "FAN_6_PRSNT_BUF_R_N")
		)
	)
	(footprint ""
		(layer "F.Cu")
		(at 27.051 -13.8938 -90)
		(property "Reference" "R4988"
			(at 0 0 270)
			(layer "F.SilkS")
			(hide yes)
			(effects
				(font
					(size 1.27 1.27)
				)
			)
		)
		(property "Value" ""
			(at 0 0 270)
			(layer "F.Fab")
			(effects
				(font
					(size 1.27 1.27)
				)
			)
		)
		(duplicate_pad_numbers_are_jumpers no)
		(fp_line
			(start -0.7874 0.4064)
			(end -0.7874 -0.4064)
			(stroke
				(width 0.1524)
				(type default)
			)
			(layer "F.SilkS")
		)
		(fp_line
			(start 0.7874 0.4064)
			(end -0.7874 0.4064)
			(stroke
				(width 0.1524)
				(type default)
			)
			(layer "F.SilkS")
		)
		(fp_line
			(start -0.7874 -0.4064)
			(end 0.7874 -0.4064)
			(stroke
				(width 0.1524)
				(type default)
			)
			(layer "F.SilkS")
		)
		(fp_line
			(start 0.7874 -0.4064)
			(end 0.7874 0.4064)
			(stroke
				(width 0.1524)
				(type default)
			)
			(layer "F.SilkS")
		)
		(fp_line
			(start -0.67945 0.3048)
			(end -0.67945 -0.305054)
			(stroke
				(width 0.1)
				(type default)
			)
			(layer "F.Fab")
		)
		(fp_line
			(start -0.12065 0.3048)
			(end -0.67945 0.3048)
			(stroke
				(width 0.1)
				(type default)
			)
			(layer "F.Fab")
		)
		(fp_line
			(start 0.120396 0.3048)
			(end 0.120396 0.2794)
			(stroke
				(width 0.1)
				(type default)
			)
			(layer "F.Fab")
		)
		(fp_line
			(start 0.67945 0.3048)
			(end 0.120396 0.3048)
			(stroke
				(width 0.1)
				(type default)
			)
			(layer "F.Fab")
		)
		(fp_line
			(start -0.12065 0.2794)
			(end -0.12065 0.3048)
			(stroke
				(width 0.1)
				(type default)
			)
			(layer "F.Fab")
		)
		(fp_line
			(start 0.120396 0.2794)
			(end -0.12065 0.2794)
			(stroke
				(width 0.1)
				(type default)
			)
			(layer "F.Fab")
		)
		(fp_line
			(start -0.12065 -0.2794)
			(end 0.12065 -0.2794)
			(stroke
				(width 0.1)
				(type default)
			)
			(layer "F.Fab")
		)
		(fp_line
			(start 0.12065 -0.2794)
			(end 0.12065 -0.3048)
			(stroke
				(width 0.1)
				(type default)
			)
			(layer "F.Fab")
		)
		(fp_line
			(start 0.12065 -0.3048)
			(end 0.67945 -0.3048)
			(stroke
				(width 0.1)
				(type default)
			)
			(layer "F.Fab")
		)
		(fp_line
			(start 0.67945 -0.3048)
			(end 0.67945 0.3048)
			(stroke
				(width 0.1)
				(type default)
			)
			(layer "F.Fab")
		)
		(fp_line
			(start -0.67945 -0.305054)
			(end -0.12065 -0.305054)
			(stroke
				(width 0.1)
				(type default)
			)
			(layer "F.Fab")
		)
		(fp_line
			(start -0.12065 -0.305054)
			(end -0.12065 -0.2794)
			(stroke
				(width 0.1)
				(type default)
			)
			(layer "F.Fab")
		)
		(pad "1" smd circle
			(at -0.40005 0 270)
			(size 0 0)
			(layers "F.Cu" "F.Mask" "F.Paste")
			(net "P3V3_AUX")
		)
		(pad "2" smd circle
			(at 0.40005 0 270)
			(size 0 0)
			(layers "F.Cu" "F.Mask" "F.Paste")
			(net "SMB_PDBV_FAN_R_SDA")
		)
	)
	(footprint ""
		(layer "F.Cu")
		(at 35.179 -114.738912 180)
		(property "Reference" "C2041"
			(at 0 0 180)
			(layer "F.SilkS")
			(hide yes)
			(effects
				(font
					(size 1.27 1.27)
				)
			)
		)
		(property "Value" ""
			(at 0 0 180)
			(layer "F.Fab")
			(effects
				(font
					(size 1.27 1.27)
				)
			)
		)
		(duplicate_pad_numbers_are_jumpers no)
		(fp_line
			(start 0.7874 0.4064)
			(end -0.7874 0.4064)
			(stroke
				(width 0.1524)
				(type default)
			)
			(layer "F.SilkS")
		)
		(fp_line
			(start 0.7874 -0.4064)
			(end 0.7874 0.4064)
			(stroke
				(width 0.1524)
				(type default)
			)
			(layer "F.SilkS")
		)
		(fp_line
			(start -0.7874 0.4064)
			(end -0.7874 -0.4064)
			(stroke
				(width 0.1524)
				(type default)
			)
			(layer "F.SilkS")
		)
		(fp_line
			(start -0.7874 -0.4064)
			(end 0.7874 -0.4064)
			(stroke
				(width 0.1524)
				(type default)
			)
			(layer "F.SilkS")
		)
		(fp_line
			(start 0.67945 0.3048)
			(end 0.120396 0.3048)
			(stroke
				(width 0.1)
				(type default)
			)
			(layer "F.Fab")
		)
		(fp_line
			(start 0.67945 -0.3048)
			(end 0.67945 0.3048)
			(stroke
				(width 0.1)
				(type default)
			)
			(layer "F.Fab")
		)
		(fp_line
			(start 0.12065 -0.2794)
			(end 0.12065 -0.3048)
			(stroke
				(width 0.1)
				(type default)
			)
			(layer "F.Fab")
		)
		(fp_line
			(start 0.12065 -0.3048)
			(end 0.67945 -0.3048)
			(stroke
				(width 0.1)
				(type default)
			)
			(layer "F.Fab")
		)
		(fp_line
			(start 0.120396 0.3048)
			(end 0.120396 0.2794)
			(stroke
				(width 0.1)
				(type default)
			)
			(layer "F.Fab")
		)
		(fp_line
			(start 0.120396 0.2794)
			(end -0.12065 0.2794)
			(stroke
				(width 0.1)
				(type default)
			)
			(layer "F.Fab")
		)
		(fp_line
			(start -0.12065 0.3048)
			(end -0.67945 0.3048)
			(stroke
				(width 0.1)
				(type default)
			)
			(layer "F.Fab")
		)
		(fp_line
			(start -0.12065 0.2794)
			(end -0.12065 0.3048)
			(stroke
				(width 0.1)
				(type default)
			)
			(layer "F.Fab")
		)
		(fp_line
			(start -0.12065 -0.2794)
			(end 0.12065 -0.2794)
			(stroke
				(width 0.1)
				(type default)
			)
			(layer "F.Fab")
		)
		(fp_line
			(start -0.12065 -0.305054)
			(end -0.12065 -0.2794)
			(stroke
				(width 0.1)
				(type default)
			)
			(layer "F.Fab")
		)
		(fp_line
			(start -0.67945 0.3048)
			(end -0.67945 -0.305054)
			(stroke
				(width 0.1)
				(type default)
			)
			(layer "F.Fab")
		)
		(fp_line
			(start -0.67945 -0.305054)
			(end -0.12065 -0.305054)
			(stroke
				(width 0.1)
				(type default)
			)
			(layer "F.Fab")
		)
		(pad "1" smd circle
			(at -0.40005 0 180)
			(size 0 0)
			(layers "F.Cu" "F.Mask" "F.Paste")
			(net "FAN_2_PWM_IL_R")
		)
		(pad "2" smd circle
			(at 0.40005 0 180)
			(size 0 0)
			(layers "F.Cu" "F.Mask" "F.Paste")
			(net "GND")
		)
	)
	(footprint ""
		(layer "F.Cu")
		(at 28.956 -167.513)
		(property "Reference" "R5469"
			(at 0 0 0)
			(layer "F.SilkS")
			(hide yes)
			(effects
				(font
					(size 1.27 1.27)
				)
			)
		)
		(property "Value" ""
			(at 0 0 0)
			(layer "F.Fab")
			(effects
				(font
					(size 1.27 1.27)
				)
			)
		)
		(duplicate_pad_numbers_are_jumpers no)
		(fp_line
			(start -0.7874 -0.4064)
			(end 0.7874 -0.4064)
			(stroke
				(width 0.1524)
				(type default)
			)
			(layer "F.SilkS")
		)
		(fp_line
			(start -0.7874 0.4064)
			(end -0.7874 -0.4064)
			(stroke
				(width 0.1524)
				(type default)
			)
			(layer "F.SilkS")
		)
		(fp_line
			(start 0.7874 -0.4064)
			(end 0.7874 0.4064)
			(stroke
				(width 0.1524)
				(type default)
			)
			(layer "F.SilkS")
		)
		(fp_line
			(start 0.7874 0.4064)
			(end -0.7874 0.4064)
			(stroke
				(width 0.1524)
				(type default)
			)
			(layer "F.SilkS")
		)
		(fp_line
			(start -0.67945 -0.305054)
			(end -0.12065 -0.305054)
			(stroke
				(width 0.1)
				(type default)
			)
			(layer "F.Fab")
		)
		(fp_line
			(start -0.67945 0.3048)
			(end -0.67945 -0.305054)
			(stroke
				(width 0.1)
				(type default)
			)
			(layer "F.Fab")
		)
		(fp_line
			(start -0.12065 -0.305054)
			(end -0.12065 -0.2794)
			(stroke
				(width 0.1)
				(type default)
			)
			(layer "F.Fab")
		)
		(fp_line
			(start -0.12065 -0.2794)
			(end 0.12065 -0.2794)
			(stroke
				(width 0.1)
				(type default)
			)
			(layer "F.Fab")
		)
		(fp_line
			(start -0.12065 0.2794)
			(end -0.12065 0.3048)
			(stroke
				(width 0.1)
				(type default)
			)
			(layer "F.Fab")
		)
		(fp_line
			(start -0.12065 0.3048)
			(end -0.67945 0.3048)
			(stroke
				(width 0.1)
				(type default)
			)
			(layer "F.Fab")
		)
		(fp_line
			(start 0.120396 0.2794)
			(end -0.12065 0.2794)
			(stroke
				(width 0.1)
				(type default)
			)
			(layer "F.Fab")
		)
		(fp_line
			(start 0.120396 0.3048)
			(end 0.120396 0.2794)
			(stroke
				(width 0.1)
				(type default)
			)
			(layer "F.Fab")
		)
		(fp_line
			(start 0.12065 -0.3048)
			(end 0.67945 -0.3048)
			(stroke
				(width 0.1)
				(type default)
			)
			(layer "F.Fab")
		)
		(fp_line
			(start 0.12065 -0.2794)
			(end 0.12065 -0.3048)
			(stroke
				(width 0.1)
				(type default)
			)
			(layer "F.Fab")
		)
		(fp_line
			(start 0.67945 -0.3048)
			(end 0.67945 0.3048)
			(stroke
				(width 0.1)
				(type default)
			)
			(layer "F.Fab")
		)
		(fp_line
			(start 0.67945 0.3048)
			(end 0.120396 0.3048)
			(stroke
				(width 0.1)
				(type default)
			)
			(layer "F.Fab")
		)
		(pad "1" smd circle
			(at -0.40005 0)
			(size 0 0)
			(layers "F.Cu" "F.Mask" "F.Paste")
			(net "SMB_PDBV_FAN_SDA")
		)
		(pad "2" smd circle
			(at 0.40005 0)
			(size 0 0)
			(layers "F.Cu" "F.Mask" "F.Paste")
			(net "SMB_PDBV_FAN_R1_IOX_SDA")
		)
	)
	(footprint ""
		(layer "F.Cu")
		(at 45.085 -189.738 180)
		(property "Reference" "R4967"
			(at 0 0 180)
			(layer "F.SilkS")
			(hide yes)
			(effects
				(font
					(size 1.27 1.27)
				)
			)
		)
		(property "Value" ""
			(at 0 0 180)
			(layer "F.Fab")
			(effects
				(font
					(size 1.27 1.27)
				)
			)
		)
		(duplicate_pad_numbers_are_jumpers no)
		(fp_line
			(start 0.7874 0.4064)
			(end -0.7874 0.4064)
			(stroke
				(width 0.1524)
				(type default)
			)
			(layer "F.SilkS")
		)
		(fp_line
			(start 0.7874 -0.4064)
			(end 0.7874 0.4064)
			(stroke
				(width 0.1524)
				(type default)
			)
			(layer "F.SilkS")
		)
		(fp_line
			(start -0.7874 0.4064)
			(end -0.7874 -0.4064)
			(stroke
				(width 0.1524)
				(type default)
			)
			(layer "F.SilkS")
		)
		(fp_line
			(start -0.7874 -0.4064)
			(end 0.7874 -0.4064)
			(stroke
				(width 0.1524)
				(type default)
			)
			(layer "F.SilkS")
		)
		(fp_line
			(start 0.67945 0.3048)
			(end 0.120396 0.3048)
			(stroke
				(width 0.1)
				(type default)
			)
			(layer "F.Fab")
		)
		(fp_line
			(start 0.67945 -0.3048)
			(end 0.67945 0.3048)
			(stroke
				(width 0.1)
				(type default)
			)
			(layer "F.Fab")
		)
		(fp_line
			(start 0.12065 -0.2794)
			(end 0.12065 -0.3048)
			(stroke
				(width 0.1)
				(type default)
			)
			(layer "F.Fab")
		)
		(fp_line
			(start 0.12065 -0.3048)
			(end 0.67945 -0.3048)
			(stroke
				(width 0.1)
				(type default)
			)
			(layer "F.Fab")
		)
		(fp_line
			(start 0.120396 0.3048)
			(end 0.120396 0.2794)
			(stroke
				(width 0.1)
				(type default)
			)
			(layer "F.Fab")
		)
		(fp_line
			(start 0.120396 0.2794)
			(end -0.12065 0.2794)
			(stroke
				(width 0.1)
				(type default)
			)
			(layer "F.Fab")
		)
		(fp_line
			(start -0.12065 0.3048)
			(end -0.67945 0.3048)
			(stroke
				(width 0.1)
				(type default)
			)
			(layer "F.Fab")
		)
		(fp_line
			(start -0.12065 0.2794)
			(end -0.12065 0.3048)
			(stroke
				(width 0.1)
				(type default)
			)
			(layer "F.Fab")
		)
		(fp_line
			(start -0.12065 -0.2794)
			(end 0.12065 -0.2794)
			(stroke
				(width 0.1)
				(type default)
			)
			(layer "F.Fab")
		)
		(fp_line
			(start -0.12065 -0.305054)
			(end -0.12065 -0.2794)
			(stroke
				(width 0.1)
				(type default)
			)
			(layer "F.Fab")
		)
		(fp_line
			(start -0.67945 0.3048)
			(end -0.67945 -0.305054)
			(stroke
				(width 0.1)
				(type default)
			)
			(layer "F.Fab")
		)
		(fp_line
			(start -0.67945 -0.305054)
			(end -0.12065 -0.305054)
			(stroke
				(width 0.1)
				(type default)
			)
			(layer "F.Fab")
		)
		(pad "1" smd circle
			(at -0.40005 0 180)
			(size 0 0)
			(layers "F.Cu" "F.Mask" "F.Paste")
			(net "GND")
		)
		(pad "2" smd circle
			(at 0.40005 0 180)
			(size 0 0)
			(layers "F.Cu" "F.Mask" "F.Paste")
			(net "PD_FAN_BUFF_INPUT_U337F")
		)
	)
	(footprint ""
		(layer "F.Cu")
		(at 47.752 -312.928 -90)
		(property "Reference" "U405"
			(at 1.64338 -2.02311 90)
			(unlocked yes)
			(layer "F.SilkS")
			(effects
				(font
					(size 0.7874 0.5842)
					(thickness 0.1524)
				)
				(justify left)
			)
		)
		(property "Value" ""
			(at 0 0 270)
			(layer "F.Fab")
			(effects
				(font
					(size 1.27 1.27)
				)
			)
		)
		(duplicate_pad_numbers_are_jumpers no)
		(fp_line
			(start -1.335278 1.100074)
			(end 1.335278 1.100074)
			(stroke
				(width 0.1524)
				(type default)
			)
			(layer "F.SilkS")
		)
		(fp_line
			(start 1.335278 1.100074)
			(end 1.335278 -1.100074)
			(stroke
				(width 0.1524)
				(type default)
			)
			(layer "F.SilkS")
		)
		(fp_line
			(start -1.335278 -1.100074)
			(end -1.335278 1.100074)
			(stroke
				(width 0.1524)
				(type default)
			)
			(layer "F.SilkS")
		)
		(fp_line
			(start 1.335278 -1.100074)
			(end -1.335278 -1.100074)
			(stroke
				(width 0.1524)
				(type default)
			)
			(layer "F.SilkS")
		)
		(fp_line
			(start -0.674878 1.100074)
			(end 0.674878 1.100074)
			(stroke
				(width 0.1)
				(type default)
			)
			(layer "F.Fab")
		)
		(fp_line
			(start 0.674878 1.100074)
			(end 0.674878 -1.100074)
			(stroke
				(width 0.1)
				(type default)
			)
			(layer "F.Fab")
		)
		(fp_line
			(start -0.674878 -1.100074)
			(end -0.674878 1.100074)
			(stroke
				(width 0.1)
				(type default)
			)
			(layer "F.Fab")
		)
		(fp_line
			(start 0.674878 -1.100074)
			(end -0.674878 -1.100074)
			(stroke
				(width 0.1)
				(type default)
			)
			(layer "F.Fab")
		)
		(pad "D" smd rect
			(at 0.8001 0 180)
			(size 0.6096 0.8128)
			(layers "F.Cu" "F.Mask" "F.Paste")
			(net "U405_D1")
		)
		(pad "G" smd rect
			(at -0.8001 -0.649986 180)
			(size 0.6096 0.8128)
			(layers "F.Cu" "F.Mask" "F.Paste")
			(net "FAN_0_PRESENT")
		)
		(pad "S" smd rect
			(at -0.8001 0.649986 180)
			(size 0.6096 0.8128)
			(layers "F.Cu" "F.Mask" "F.Paste")
			(net "GND")
		)
	)
)
